(kicad_pcb
	(version 20221018)
	(generator pcbnew)
	(general
    (thickness 1.6)
  )
	(paper "A4")
	(title_block
    (title "NUC Computer Cluster Power Breakout HW")
    (date "2023-10-18")
    (rev "1.4.3")
    (company "Antmicro Ltd.")
		(comment 9 "footprints 20-24 of 234")
	)
	(layers
    (0 "F.Cu" mixed)
    (1 "In1.Cu" power)
    (2 "In2.Cu" mixed)
    (31 "B.Cu" power)
    (32 "B.Adhes" user "B.Adhesive")
    (33 "F.Adhes" user "F.Adhesive")
    (34 "B.Paste" user)
    (35 "F.Paste" user)
    (36 "B.SilkS" user "B.Silkscreen")
    (37 "F.SilkS" user "F.Silkscreen")
    (38 "B.Mask" user)
    (39 "F.Mask" user)
    (40 "Dwgs.User" user "User.Drawings")
    (41 "Cmts.User" user "User.Comments")
    (42 "Eco1.User" user "User.Eco1")
    (43 "Eco2.User" user "User.Eco2")
    (44 "Edge.Cuts" user)
    (45 "Margin" user)
    (46 "B.CrtYd" user "B.Courtyard")
    (47 "F.CrtYd" user "F.Courtyard")
    (48 "B.Fab" user)
    (49 "F.Fab" user)
  )
	(footprint "antmicro-footprints:SOT-23-3" (layer "F.Cu")
    (at 163.35 86.95)
    (property "Author" "Antmicro")
    (property "License" "Apache-2.0")
    (property "MPN" "2N7002")
    (property "Manufacturer" "ON Semiconductor")
    (property "Sheetfile" "power-switch.kicad_sch")
    (property "Sheetname" "Power switch 4")
    (property "ki_description" "Power MOSFET, N Channel, 60 V, 115 mA, 1.2 ohm, SOT-23, Surface Mount")
    (property "ki_keywords" "SMT, TRANSISTOR, SEMICONDUCTOR, NMOS")
    (attr smd)
    (fp_text reference "Q9" (at 0.1 2.6) (layer "F.SilkS")
        (effects (font (size 0.7 0.7) (thickness 0.15)) (justify left bottom))
    )
    (fp_text value "2N7002_SOT-23-3" (at -1.9 2.7) (layer "F.Fab")
        (effects (font (size 0.7 0.7) (thickness 0.15)) (justify left bottom))
    )
    (fp_text user "License: Apache-2.0" (at -1.8 6.8) (layer "F.Fab") hide
        (effects (font (size 0.7 0.7) (thickness 0.15)) (justify left bottom))
    )
    (fp_text user "${REFERENCE}" (at -1.837 4) (layer "F.Fab") hide
        (effects (font (size 0.7 0.7) (thickness 0.15)) (justify left bottom))
    )
    (fp_text user "Author: Antmicro" (at -1.837 5.3) (layer "F.Fab") hide
        (effects (font (size 0.7 0.7) (thickness 0.15)) (justify left bottom))
    )
    (fp_line (start -1.45 -1.35) (end -0.85 -1.35)
      (stroke (width 0.15) (type solid)) (layer "F.SilkS"))
    (fp_line (start -0.85 -1.35) (end -0.7 -1.5)
      (stroke (width 0.15) (type solid)) (layer "F.SilkS"))
    (fp_line (start -0.7 1.5) (end -0.7 1.35)
      (stroke (width 0.15) (type solid)) (layer "F.SilkS"))
    (fp_line (start 0.7 -1.5) (end -0.7 -1.5)
      (stroke (width 0.15) (type solid)) (layer "F.SilkS"))
    (fp_line (start 0.7 -0.4) (end 0.7 -1.5)
      (stroke (width 0.15) (type solid)) (layer "F.SilkS"))
    (fp_line (start 0.7 0.4) (end 0.7 1.5)
      (stroke (width 0.15) (type solid)) (layer "F.SilkS"))
    (fp_line (start 0.7 1.5) (end -0.7 1.5)
      (stroke (width 0.15) (type solid)) (layer "F.SilkS"))
    (fp_line (start -1.75 -0.5) (end -1.75 -1.4)
      (stroke (width 0.05) (type solid)) (layer "F.CrtYd"))
    (fp_line (start -1.75 0.5) (end -0.85 0.5)
      (stroke (width 0.05) (type solid)) (layer "F.CrtYd"))
    (fp_line (start -1.75 1.4) (end -1.75 0.5)
      (stroke (width 0.05) (type solid)) (layer "F.CrtYd"))
    (fp_line (start -0.9 -1.6) (end -0.9 -1.4)
      (stroke (width 0.05) (type solid)) (layer "F.CrtYd"))
    (fp_line (start -0.9 -1.6) (end 0.825 -1.6)
      (stroke (width 0.05) (type solid)) (layer "F.CrtYd"))
    (fp_line (start -0.9 -1.4) (end -1.75 -1.4)
      (stroke (width 0.05) (type solid)) (layer "F.CrtYd"))
    (fp_line (start -0.85 -0.5) (end -1.75 -0.5)
      (stroke (width 0.05) (type solid)) (layer "F.CrtYd"))
    (fp_line (start -0.85 0.5) (end -0.85 -0.5)
      (stroke (width 0.05) (type solid)) (layer "F.CrtYd"))
    (fp_line (start -0.85 1.4) (end -1.75 1.4)
      (stroke (width 0.05) (type solid)) (layer "F.CrtYd"))
    (fp_line (start -0.85 1.65) (end -0.85 1.4)
      (stroke (width 0.05) (type solid)) (layer "F.CrtYd"))
    (fp_line (start 0.825 -1.6) (end 0.825 -0.45)
      (stroke (width 0.05) (type solid)) (layer "F.CrtYd"))
    (fp_line (start 0.825 -0.45) (end 1.75 -0.45)
      (stroke (width 0.05) (type solid)) (layer "F.CrtYd"))
    (fp_line (start 0.85 0.45) (end 0.85 1.65)
      (stroke (width 0.05) (type solid)) (layer "F.CrtYd"))
    (fp_line (start 0.85 1.65) (end -0.85 1.65)
      (stroke (width 0.05) (type solid)) (layer "F.CrtYd"))
    (fp_line (start 1.75 -0.45) (end 1.75 0.45)
      (stroke (width 0.05) (type solid)) (layer "F.CrtYd"))
    (fp_line (start 1.75 0.45) (end 0.85 0.45)
      (stroke (width 0.05) (type solid)) (layer "F.CrtYd"))
    (fp_line (start -0.712 -1.325) (end -0.712 1.523)
      (stroke (width 0.15) (type solid)) (layer "F.Fab"))
    (fp_line (start -0.712 1.519) (end 0.688 1.519)
      (stroke (width 0.15) (type solid)) (layer "F.Fab"))
    (fp_line (start -0.437 -1.526) (end -0.712 -1.325)
      (stroke (width 0.15) (type solid)) (layer "F.Fab"))
    (fp_line (start -0.437 -1.526) (end 0.688 -1.526)
      (stroke (width 0.15) (type solid)) (layer "F.Fab"))
    (fp_line (start 0.688 1.519) (end 0.688 -1.52)
      (stroke (width 0.15) (type solid)) (layer "F.Fab"))
    (pad "1" smd roundrect (at -1.1 -0.951) (size 1 0.6) (layers "F.Cu" "F.Paste" "F.Mask") (roundrect_rratio 0.15)
      (net 29 "/Power Cycling & Current Measurement/PC_4") (pinfunction "G") (pintype "passive"))
    (pad "2" smd roundrect (at -1.1 0.949) (size 1 0.6) (layers "F.Cu" "F.Paste" "F.Mask") (roundrect_rratio 0.15)
      (net 4 "GND") (pinfunction "S") (pintype "passive"))
    (pad "3" smd roundrect (at 1.1 -0.0005) (size 1 0.6) (layers "F.Cu" "F.Paste" "F.Mask") (roundrect_rratio 0.15)
      (net 85 "Net-(D17-A)") (pinfunction "D") (pintype "passive"))
  )
	(footprint "antmicro-footprints:SOT-23-3" (layer "F.Cu")
    (at 146.4 86.95)
    (property "Author" "Antmicro")
    (property "License" "Apache-2.0")
    (property "MPN" "2N7002")
    (property "Manufacturer" "ON Semiconductor")
    (property "Sheetfile" "power-switch.kicad_sch")
    (property "Sheetname" "Power switch 3")
    (property "ki_description" "Power MOSFET, N Channel, 60 V, 115 mA, 1.2 ohm, SOT-23, Surface Mount")
    (property "ki_keywords" "SMT, TRANSISTOR, SEMICONDUCTOR, NMOS")
    (attr smd)
    (fp_text reference "Q8" (at 0.5 2.6) (layer "F.SilkS")
        (effects (font (size 0.7 0.7) (thickness 0.15)) (justify left bottom))
    )
    (fp_text value "2N7002_SOT-23-3" (at -1.9 2.7) (layer "F.Fab")
        (effects (font (size 0.7 0.7) (thickness 0.15)) (justify left bottom))
    )
    (fp_text user "Author: Antmicro" (at -1.837 5.3) (layer "F.Fab") hide
        (effects (font (size 0.7 0.7) (thickness 0.15)) (justify left bottom))
    )
    (fp_text user "License: Apache-2.0" (at -1.8 6.8) (layer "F.Fab") hide
        (effects (font (size 0.7 0.7) (thickness 0.15)) (justify left bottom))
    )
    (fp_text user "${REFERENCE}" (at -1.837 4) (layer "F.Fab") hide
        (effects (font (size 0.7 0.7) (thickness 0.15)) (justify left bottom))
    )
    (fp_line (start -1.45 -1.35) (end -0.85 -1.35)
      (stroke (width 0.15) (type solid)) (layer "F.SilkS"))
    (fp_line (start -0.85 -1.35) (end -0.7 -1.5)
      (stroke (width 0.15) (type solid)) (layer "F.SilkS"))
    (fp_line (start -0.7 1.5) (end -0.7 1.35)
      (stroke (width 0.15) (type solid)) (layer "F.SilkS"))
    (fp_line (start 0.7 -1.5) (end -0.7 -1.5)
      (stroke (width 0.15) (type solid)) (layer "F.SilkS"))
    (fp_line (start 0.7 -0.4) (end 0.7 -1.5)
      (stroke (width 0.15) (type solid)) (layer "F.SilkS"))
    (fp_line (start 0.7 0.4) (end 0.7 1.5)
      (stroke (width 0.15) (type solid)) (layer "F.SilkS"))
    (fp_line (start 0.7 1.5) (end -0.7 1.5)
      (stroke (width 0.15) (type solid)) (layer "F.SilkS"))
    (fp_line (start -1.75 -0.5) (end -1.75 -1.4)
      (stroke (width 0.05) (type solid)) (layer "F.CrtYd"))
    (fp_line (start -1.75 0.5) (end -0.85 0.5)
      (stroke (width 0.05) (type solid)) (layer "F.CrtYd"))
    (fp_line (start -1.75 1.4) (end -1.75 0.5)
      (stroke (width 0.05) (type solid)) (layer "F.CrtYd"))
    (fp_line (start -0.9 -1.6) (end -0.9 -1.4)
      (stroke (width 0.05) (type solid)) (layer "F.CrtYd"))
    (fp_line (start -0.9 -1.6) (end 0.825 -1.6)
      (stroke (width 0.05) (type solid)) (layer "F.CrtYd"))
    (fp_line (start -0.9 -1.4) (end -1.75 -1.4)
      (stroke (width 0.05) (type solid)) (layer "F.CrtYd"))
    (fp_line (start -0.85 -0.5) (end -1.75 -0.5)
      (stroke (width 0.05) (type solid)) (layer "F.CrtYd"))
    (fp_line (start -0.85 0.5) (end -0.85 -0.5)
      (stroke (width 0.05) (type solid)) (layer "F.CrtYd"))
    (fp_line (start -0.85 1.4) (end -1.75 1.4)
      (stroke (width 0.05) (type solid)) (layer "F.CrtYd"))
    (fp_line (start -0.85 1.65) (end -0.85 1.4)
      (stroke (width 0.05) (type solid)) (layer "F.CrtYd"))
    (fp_line (start 0.825 -1.6) (end 0.825 -0.45)
      (stroke (width 0.05) (type solid)) (layer "F.CrtYd"))
    (fp_line (start 0.825 -0.45) (end 1.75 -0.45)
      (stroke (width 0.05) (type solid)) (layer "F.CrtYd"))
    (fp_line (start 0.85 0.45) (end 0.85 1.65)
      (stroke (width 0.05) (type solid)) (layer "F.CrtYd"))
    (fp_line (start 0.85 1.65) (end -0.85 1.65)
      (stroke (width 0.05) (type solid)) (layer "F.CrtYd"))
    (fp_line (start 1.75 -0.45) (end 1.75 0.45)
      (stroke (width 0.05) (type solid)) (layer "F.CrtYd"))
    (fp_line (start 1.75 0.45) (end 0.85 0.45)
      (stroke (width 0.05) (type solid)) (layer "F.CrtYd"))
    (fp_line (start -0.712 -1.325) (end -0.712 1.523)
      (stroke (width 0.15) (type solid)) (layer "F.Fab"))
    (fp_line (start -0.712 1.519) (end 0.688 1.519)
      (stroke (width 0.15) (type solid)) (layer "F.Fab"))
    (fp_line (start -0.437 -1.526) (end -0.712 -1.325)
      (stroke (width 0.15) (type solid)) (layer "F.Fab"))
    (fp_line (start -0.437 -1.526) (end 0.688 -1.526)
      (stroke (width 0.15) (type solid)) (layer "F.Fab"))
    (fp_line (start 0.688 1.519) (end 0.688 -1.52)
      (stroke (width 0.15) (type solid)) (layer "F.Fab"))
    (pad "1" smd roundrect (at -1.1 -0.951) (size 1 0.6) (layers "F.Cu" "F.Paste" "F.Mask") (roundrect_rratio 0.15)
      (net 30 "/Power Cycling & Current Measurement/PC_3") (pinfunction "G") (pintype "passive"))
    (pad "2" smd roundrect (at -1.1 0.949) (size 1 0.6) (layers "F.Cu" "F.Paste" "F.Mask") (roundrect_rratio 0.15)
      (net 4 "GND") (pinfunction "S") (pintype "passive"))
    (pad "3" smd roundrect (at 1.1 -0.0005) (size 1 0.6) (layers "F.Cu" "F.Paste" "F.Mask") (roundrect_rratio 0.15)
      (net 86 "Net-(D18-A)") (pinfunction "D") (pintype "passive"))
  )
	(footprint "antmicro-footprints:C_0402_1005Metric" (layer "F.Cu")
    (at 143.9775 84.5775 -90)
    (descr "Capacitor SMD 0402")
    (tags "capacitor SMD 0402")
    (property "Author" "Antmicro")
    (property "Dielectric" "X5R")
    (property "License" "Apache-2.0")
    (property "MPN" "GRM155R61H104KE14D")
    (property "Manufacturer" "Murata")
    (property "Sheetfile" "pow-cycl-curr-meas.kicad_sch")
    (property "Sheetname" "Power Cycling & Current Measurement")
    (property "Val" "100n")
    (property "Voltage" "50V")
    (property "ki_description" "SMD Multilayer Ceramic Capacitor, 0.1 µF, 50 V, 0402 [1005 Metric], ± 10%, X5R, GRM Series")
    (property "ki_keywords" "0402, SMT, CAPACITOR, PASSIVE, CERAMIC, MLCC")
    (attr smd)
    (fp_text reference "C32" (at 1.0225 0.8775 90) (layer "F.SilkS")
        (effects (font (size 0.7 0.7) (thickness 0.15)))
    )
    (fp_text value "C_100n_0402" (at 0 1.17 90) (layer "F.Fab") hide
        (effects (font (size 1 1) (thickness 0.15)))
    )
    (fp_text user "Author: Antmicro" (at -0.939 3.399 -90) (layer "F.Fab") hide
        (effects (font (size 0.7 0.7) (thickness 0.15)) (justify left bottom))
    )
    (fp_text user "${REFERENCE}" (at 0 0 90) (layer "F.Fab")
        (effects (font (size 0.7 0.7) (thickness 0.15)))
    )
    (fp_text user "License: Apache-2.0" (at -0.939 5.799 -90) (layer "F.Fab") hide
        (effects (font (size 0.7 0.7) (thickness 0.15)) (justify left bottom))
    )
    (fp_rect (start -0.925 -0.47) (end 0.925 0.47)
      (stroke (width 0.05) (type default)) (fill none) (layer "F.CrtYd"))
    (fp_line (start -0.494 -0.25) (end 0.504 -0.25)
      (stroke (width 0.15) (type solid)) (layer "F.Fab"))
    (fp_line (start -0.494 0.248) (end -0.494 -0.25)
      (stroke (width 0.15) (type solid)) (layer "F.Fab"))
    (fp_line (start 0.504 -0.25) (end 0.504 0.248)
      (stroke (width 0.15) (type solid)) (layer "F.Fab"))
    (fp_line (start 0.504 0.248) (end -0.494 0.248)
      (stroke (width 0.15) (type solid)) (layer "F.Fab"))
    (pad "1" smd roundrect (at -0.48 0 270) (size 0.59 0.64) (layers "F.Cu" "F.Paste" "F.Mask") (roundrect_rratio 0.25)
      (net 1 "VCC3V3") (pintype "passive"))
    (pad "2" smd roundrect (at 0.48 0 270) (size 0.59 0.64) (layers "F.Cu" "F.Paste" "F.Mask") (roundrect_rratio 0.25)
      (net 4 "GND") (pintype "passive"))
  )
	(footprint "antmicro-footprints:SOIC-8_3.9x4.9x1.75mm_P1.27mm" (layer "F.Cu")
    (at 131.67 82.15 180)
    (property "Author" "Antmicro")
    (property "License" "Apache-2.0")
    (property "MPN" "TMCS1100A2QDRQ1")
    (property "Manufacturer" "Texas Instruments")
    (property "Sheetfile" "pow-cycl-curr-meas.kicad_sch")
    (property "Sheetname" "Power Cycling & Current Measurement")
    (property "ki_description" "Hall current Sensor/transducer")
    (property "ki_keywords" "SMT, SENSOR, IC, POWER")
    (attr smd)
    (fp_text reference "U9" (at 1.42 2.8) (layer "F.SilkS")
        (effects (font (size 0.7 0.7) (thickness 0.15)) (justify right bottom))
    )
    (fp_text value "TMCS1100A2-Q1" (at 0 3.65) (layer "F.Fab")
        (effects (font (size 0.7 0.7) (thickness 0.15)) (justify right bottom))
    )
    (fp_text user "${REFERENCE}" (at -3.476 7.099) (layer "F.Fab") hide
        (effects (font (size 0.7 0.7) (thickness 0.15)) (justify right bottom))
    )
    (fp_text user "License: Apache-2.0" (at -3.476 5.099) (layer "F.Fab") hide
        (effects (font (size 0.7 0.7) (thickness 0.15)) (justify right bottom))
    )
    (fp_text user "Author: Antmicro" (at -3.476 6.099) (layer "F.Fab") hide
        (effects (font (size 0.7 0.7) (thickness 0.15)) (justify right bottom))
    )
    (fp_line (start -1.95 -2.452) (end 1.95 -2.45)
      (stroke (width 0.15) (type solid)) (layer "F.SilkS"))
    (fp_line (start -1.95 2.45) (end 1.95 2.45)
      (stroke (width 0.15) (type solid)) (layer "F.SilkS"))
    (fp_circle (center -2.4 -2.45) (end -2.35 -2.4)
      (stroke (width 0.15) (type solid)) (fill solid) (layer "F.SilkS"))
    (fp_rect (start -3.625 -2.7) (end 3.625 2.7)
      (stroke (width 0.05) (type solid)) (fill none) (layer "F.CrtYd"))
    (fp_line (start -1.95 -1.18) (end -0.683 -2.452)
      (stroke (width 0.15) (type solid)) (layer "F.Fab"))
    (fp_line (start -1.95 2.45) (end -1.95 -1.18)
      (stroke (width 0.15) (type solid)) (layer "F.Fab"))
    (fp_line (start -0.683 -2.452) (end 1.949 -2.452)
      (stroke (width 0.15) (type solid)) (layer "F.Fab"))
    (fp_line (start 1.949 -2.452) (end 1.949 2.45)
      (stroke (width 0.15) (type solid)) (layer "F.Fab"))
    (fp_line (start 1.949 2.45) (end -1.95 2.45)
      (stroke (width 0.15) (type solid)) (layer "F.Fab"))
    (pad "1" smd roundrect (at -2.714 -1.905 270) (size 0.65 1.525) (layers "F.Cu" "F.Paste" "F.Mask") (roundrect_rratio 0.25)
      (net 22 "C_MEAS_2") (pinfunction "IN+") (pintype "input"))
    (pad "2" smd roundrect (at -2.714 -0.635 270) (size 0.65 1.525) (layers "F.Cu" "F.Paste" "F.Mask") (roundrect_rratio 0.25)
      (net 22 "C_MEAS_2") (pinfunction "IN+") (pintype "input"))
    (pad "3" smd roundrect (at -2.714 0.632 270) (size 0.65 1.525) (layers "F.Cu" "F.Paste" "F.Mask") (roundrect_rratio 0.25)
      (net 44 "LOAD_2") (pinfunction "IN-") (pintype "input"))
    (pad "4" smd roundrect (at -2.714 1.902 270) (size 0.65 1.525) (layers "F.Cu" "F.Paste" "F.Mask") (roundrect_rratio 0.25)
      (net 44 "LOAD_2") (pinfunction "IN-") (pintype "input"))
    (pad "5" smd roundrect (at 2.712 1.902 270) (size 0.65 1.525) (layers "F.Cu" "F.Paste" "F.Mask") (roundrect_rratio 0.25)
      (net 4 "GND") (pinfunction "GND") (pintype "power_in"))
    (pad "6" smd roundrect (at 2.712 0.632 270) (size 0.65 1.525) (layers "F.Cu" "F.Paste" "F.Mask") (roundrect_rratio 0.25)
      (net 4 "GND") (pinfunction "VREF") (pintype "input"))
    (pad "7" smd roundrect (at 2.712 -0.635 270) (size 0.65 1.525) (layers "F.Cu" "F.Paste" "F.Mask") (roundrect_rratio 0.25)
      (net 47 "/Power Cycling & Current Measurement/C_ADC2") (pinfunction "VOUT") (pintype "output"))
    (pad "8" smd roundrect (at 2.712 -1.905 270) (size 0.65 1.525) (layers "F.Cu" "F.Paste" "F.Mask") (roundrect_rratio 0.25)
      (net 1 "VCC3V3") (pinfunction "VCC") (pintype "power_in"))
  )
	(footprint "antmicro-footprints:C_0402_1005Metric" (layer "F.Cu")
    (at 160.9 84.55 -90)
    (descr "Capacitor SMD 0402")
    (tags "capacitor SMD 0402")
    (property "Author" "Antmicro")
    (property "Dielectric" "X5R")
    (property "License" "Apache-2.0")
    (property "MPN" "GRM155R61H104KE14D")
    (property "Manufacturer" "Murata")
    (property "Sheetfile" "pow-cycl-curr-meas.kicad_sch")
    (property "Sheetname" "Power Cycling & Current Measurement")
    (property "Val" "100n")
    (property "Voltage" "50V")
    (property "ki_description" "SMD Multilayer Ceramic Capacitor, 0.1 µF, 50 V, 0402 [1005 Metric], ± 10%, X5R, GRM Series")
    (property "ki_keywords" "0402, SMT, CAPACITOR, PASSIVE, CERAMIC, MLCC")
    (attr smd)
    (fp_text reference "C31" (at 0.95 0.9 90) (layer "F.SilkS")
        (effects (font (size 0.7 0.7) (thickness 0.15)))
    )
    (fp_text value "C_100n_0402" (at 0 1.17 90) (layer "F.Fab") hide
        (effects (font (size 1 1) (thickness 0.15)))
    )
    (fp_text user "License: Apache-2.0" (at -0.939 5.799 -90) (layer "F.Fab") hide
        (effects (font (size 0.7 0.7) (thickness 0.15)) (justify left bottom))
    )
    (fp_text user "Author: Antmicro" (at -0.939 3.399 -90) (layer "F.Fab") hide
        (effects (font (size 0.7 0.7) (thickness 0.15)) (justify left bottom))
    )
    (fp_text user "${REFERENCE}" (at 0 0 90) (layer "F.Fab")
        (effects (font (size 0.7 0.7) (thickness 0.15)))
    )
    (fp_rect (start -0.925 -0.47) (end 0.925 0.47)
      (stroke (width 0.05) (type default)) (fill none) (layer "F.CrtYd"))
    (fp_line (start -0.494 -0.25) (end 0.504 -0.25)
      (stroke (width 0.15) (type solid)) (layer "F.Fab"))
    (fp_line (start -0.494 0.248) (end -0.494 -0.25)
      (stroke (width 0.15) (type solid)) (layer "F.Fab"))
    (fp_line (start 0.504 -0.25) (end 0.504 0.248)
      (stroke (width 0.15) (type solid)) (layer "F.Fab"))
    (fp_line (start 0.504 0.248) (end -0.494 0.248)
      (stroke (width 0.15) (type solid)) (layer "F.Fab"))
    (pad "1" smd roundrect (at -0.48 0 270) (size 0.59 0.64) (layers "F.Cu" "F.Paste" "F.Mask") (roundrect_rratio 0.25)
      (net 1 "VCC3V3") (pintype "passive"))
    (pad "2" smd roundrect (at 0.48 0 270) (size 0.59 0.64) (layers "F.Cu" "F.Paste" "F.Mask") (roundrect_rratio 0.25)
      (net 4 "GND") (pintype "passive"))
  )
)
